# T6G (Grand Teton) — schematic netlist excerpt (pin names and nets, part order shuffled) for the footprints in the layout excerpt that follows; sources: Cadence DE-HDL packaged netlist, KiCad conversion of 04192023_DAF0TMB3IC0_F0TG_MB_C_brd_V02_OCP.brd

R4158  Q_RES  54.9K 1% EMPTY  pkg 0402LF  page 124 : A = P3V3_AUX ; B = GPU_3V3IO_RSVD1
R6243  Q_RES  10K 1% CHIP  pkg 0402LF  page 269 : A = P3V3_AUX ; B = PWRGD_P1V8_AUX
C1331  Q_CAP  10UF 16V 10% X6S  pkg C0805  page 188 : A = P5V ; B = GND

(kicad_pcb
	(version 20260206)
	(generator "pcbnew")
	(generator_version "10.0")
	(general
		(thickness 1.6)
		(legacy_teardrops no)
	)
	(paper "A4")
	(title_block
		(title "04192023_DAF0TMB3IC0_F0TG_MB_C_brd_V02_OCP.brd")
		(comment 1 "Grand Teton / footprints 319-321 of 8354")
	)
	(layers
		(0 "F.Cu" signal "TOP")
		(4 "In1.Cu" signal "GND")
		(6 "In2.Cu" signal "IN1")
		(8 "In3.Cu" signal "GND1")
		(10 "In4.Cu" signal "IN2")
		(12 "In5.Cu" signal "GND2")
		(14 "In6.Cu" signal "IN3")
		(16 "In7.Cu" signal "GND3")
		(18 "In8.Cu" signal "VCC")
		(20 "In9.Cu" signal "VCC1")
		(22 "In10.Cu" signal "GND4")
		(24 "In11.Cu" signal "IN4")
		(26 "In12.Cu" signal "GND5")
		(28 "In13.Cu" signal "IN5")
		(30 "In14.Cu" signal "GND6")
		(32 "In15.Cu" signal "IN6")
		(34 "In16.Cu" signal "GND7")
		(2 "B.Cu" signal "BOTTOM")
		(9 "F.Adhes" user "F.Adhesive")
		(11 "B.Adhes" user "B.Adhesive")
		(13 "F.Paste" user "Package Geometry/Pastemask Top")
		(15 "B.Paste" user "Package Geometry/Pastemask Bottom")
		(5 "F.SilkS" user "Ref Des/Silkscreen Top")
		(7 "B.SilkS" user "Ref Des/Silkscreen Bottom")
		(1 "F.Mask" user "Board Geometry/Soldermask Top")
		(3 "B.Mask" user "Board Geometry/Soldermask Bottom")
		(17 "Dwgs.User" user "User.Drawings")
		(19 "Cmts.User" user "User.Comments")
		(21 "Eco1.User" user "User.Eco1")
		(23 "Eco2.User" user "User.Eco2")
		(25 "Edge.Cuts" user "Board Geometry/Outline")
		(27 "Margin" user)
		(31 "F.CrtYd" user "Package Geometry/Place Bound Top")
		(29 "B.CrtYd" user "Package Geometry/Place Bound Bottom")
		(35 "F.Fab" user "Ref Des/Assembly Top")
		(33 "B.Fab" user "Ref Des/Assembly Bottom")
	)
	(footprint ""
		(layer "F.Cu")
		(at 420.246302 -436.164736 -90)
		(property "Reference" "R4158"
			(at 0 0 270)
			(layer "F.SilkS")
			(hide yes)
			(effects
				(font
					(size 1.27 1.27)
				)
			)
		)
		(property "Value" ""
			(at 0 0 270)
			(layer "F.Fab")
			(effects
				(font
					(size 1.27 1.27)
				)
			)
		)
		(duplicate_pad_numbers_are_jumpers no)
		(fp_line
			(start -0.7874 0.4064)
			(end -0.7874 -0.4064)
			(stroke
				(width 0.1524)
				(type default)
			)
			(layer "F.SilkS")
		)
		(fp_line
			(start 0.7874 0.4064)
			(end -0.7874 0.4064)
			(stroke
				(width 0.1524)
				(type default)
			)
			(layer "F.SilkS")
		)
		(fp_line
			(start -0.7874 -0.4064)
			(end 0.7874 -0.4064)
			(stroke
				(width 0.1524)
				(type default)
			)
			(layer "F.SilkS")
		)
		(fp_line
			(start 0.7874 -0.4064)
			(end 0.7874 0.4064)
			(stroke
				(width 0.1524)
				(type default)
			)
			(layer "F.SilkS")
		)
		(fp_line
			(start -0.67945 0.3048)
			(end -0.67945 -0.305054)
			(stroke
				(width 0.1)
				(type default)
			)
			(layer "F.Fab")
		)
		(fp_line
			(start -0.12065 0.3048)
			(end -0.67945 0.3048)
			(stroke
				(width 0.1)
				(type default)
			)
			(layer "F.Fab")
		)
		(fp_line
			(start 0.120396 0.3048)
			(end 0.120396 0.2794)
			(stroke
				(width 0.1)
				(type default)
			)
			(layer "F.Fab")
		)
		(fp_line
			(start 0.67945 0.3048)
			(end 0.120396 0.3048)
			(stroke
				(width 0.1)
				(type default)
			)
			(layer "F.Fab")
		)
		(fp_line
			(start -0.12065 0.2794)
			(end -0.12065 0.3048)
			(stroke
				(width 0.1)
				(type default)
			)
			(layer "F.Fab")
		)
		(fp_line
			(start 0.120396 0.2794)
			(end -0.12065 0.2794)
			(stroke
				(width 0.1)
				(type default)
			)
			(layer "F.Fab")
		)
		(fp_line
			(start -0.12065 -0.2794)
			(end 0.12065 -0.2794)
			(stroke
				(width 0.1)
				(type default)
			)
			(layer "F.Fab")
		)
		(fp_line
			(start 0.12065 -0.2794)
			(end 0.12065 -0.3048)
			(stroke
				(width 0.1)
				(type default)
			)
			(layer "F.Fab")
		)
		(fp_line
			(start 0.12065 -0.3048)
			(end 0.67945 -0.3048)
			(stroke
				(width 0.1)
				(type default)
			)
			(layer "F.Fab")
		)
		(fp_line
			(start 0.67945 -0.3048)
			(end 0.67945 0.3048)
			(stroke
				(width 0.1)
				(type default)
			)
			(layer "F.Fab")
		)
		(fp_line
			(start -0.67945 -0.305054)
			(end -0.12065 -0.305054)
			(stroke
				(width 0.1)
				(type default)
			)
			(layer "F.Fab")
		)
		(fp_line
			(start -0.12065 -0.305054)
			(end -0.12065 -0.2794)
			(stroke
				(width 0.1)
				(type default)
			)
			(layer "F.Fab")
		)
		(pad "1" smd circle
			(at -0.40005 0 270)
			(size 0 0)
			(layers "F.Cu" "F.Mask" "F.Paste")
			(net "P3V3_AUX")
		)
		(pad "2" smd circle
			(at 0.40005 0 270)
			(size 0 0)
			(layers "F.Cu" "F.Mask" "F.Paste")
			(net "GPU_3V3IO_RSVD1")
		)
	)
	(footprint ""
		(layer "F.Cu")
		(at 398.06245 -146.148552 -90)
		(property "Reference" "C1331"
			(at 0 0 270)
			(layer "F.SilkS")
			(hide yes)
			(effects
				(font
					(size 1.27 1.27)
				)
			)
		)
		(property "Value" ""
			(at 0 0 270)
			(layer "F.Fab")
			(effects
				(font
					(size 1.27 1.27)
				)
			)
		)
		(duplicate_pad_numbers_are_jumpers no)
		(fp_line
			(start -1.524 0.762)
			(end -1.524 -0.762)
			(stroke
				(width 0.1524)
				(type default)
			)
			(layer "F.SilkS")
		)
		(fp_line
			(start 1.524 0.762)
			(end -1.524 0.762)
			(stroke
				(width 0.1524)
				(type default)
			)
			(layer "F.SilkS")
		)
		(fp_line
			(start -1.524 -0.762)
			(end 1.524 -0.762)
			(stroke
				(width 0.1524)
				(type default)
			)
			(layer "F.SilkS")
		)
		(fp_line
			(start 1.524 -0.762)
			(end 1.524 0.762)
			(stroke
				(width 0.1524)
				(type default)
			)
			(layer "F.SilkS")
		)
		(fp_line
			(start -1.1049 0.724916)
			(end 1.1049 0.724916)
			(stroke
				(width 0.1)
				(type default)
			)
			(layer "F.Fab")
		)
		(fp_line
			(start 1.1049 0.724916)
			(end 1.1049 -0.724916)
			(stroke
				(width 0.1)
				(type default)
			)
			(layer "F.Fab")
		)
		(fp_line
			(start -1.1049 -0.724916)
			(end -1.1049 0.724916)
			(stroke
				(width 0.1)
				(type default)
			)
			(layer "F.Fab")
		)
		(fp_line
			(start 1.1049 -0.724916)
			(end -1.1049 -0.724916)
			(stroke
				(width 0.1)
				(type default)
			)
			(layer "F.Fab")
		)
		(pad "1" smd rect
			(at -0.889 0 90)
			(size 1.016 1.27)
			(layers "F.Cu" "F.Mask" "F.Paste")
			(net "P5V")
		)
		(pad "2" smd rect
			(at 0.889 0 90)
			(size 1.016 1.27)
			(layers "F.Cu" "F.Mask" "F.Paste")
			(net "GND")
		)
	)
	(footprint ""
		(layer "F.Cu")
		(at 145.823178 -75.115166 90)
		(property "Reference" "R6243"
			(at 0 0 90)
			(layer "F.SilkS")
			(hide yes)
			(effects
				(font
					(size 1.27 1.27)
				)
			)
		)
		(property "Value" ""
			(at 0 0 90)
			(layer "F.Fab")
			(effects
				(font
					(size 1.27 1.27)
				)
			)
		)
		(duplicate_pad_numbers_are_jumpers no)
		(fp_line
			(start 0.7874 -0.4064)
			(end 0.7874 0.4064)
			(stroke
				(width 0.1524)
				(type default)
			)
			(layer "F.SilkS")
		)
		(fp_line
			(start -0.7874 -0.4064)
			(end 0.7874 -0.4064)
			(stroke
				(width 0.1524)
				(type default)
			)
			(layer "F.SilkS")
		)
		(fp_line
			(start 0.7874 0.4064)
			(end -0.7874 0.4064)
			(stroke
				(width 0.1524)
				(type default)
			)
			(layer "F.SilkS")
		)
		(fp_line
			(start -0.7874 0.4064)
			(end -0.7874 -0.4064)
			(stroke
				(width 0.1524)
				(type default)
			)
			(layer "F.SilkS")
		)
		(fp_line
			(start -0.12065 -0.305054)
			(end -0.12065 -0.2794)
			(stroke
				(width 0.1)
				(type default)
			)
			(layer "F.Fab")
		)
		(fp_line
			(start -0.67945 -0.305054)
			(end -0.12065 -0.305054)
			(stroke
				(width 0.1)
				(type default)
			)
			(layer "F.Fab")
		)
		(fp_line
			(start 0.67945 -0.3048)
			(end 0.67945 0.3048)
			(stroke
				(width 0.1)
				(type default)
			)
			(layer "F.Fab")
		)
		(fp_line
			(start 0.12065 -0.3048)
			(end 0.67945 -0.3048)
			(stroke
				(width 0.1)
				(type default)
			)
			(layer "F.Fab")
		)
		(fp_line
			(start 0.12065 -0.2794)
			(end 0.12065 -0.3048)
			(stroke
				(width 0.1)
				(type default)
			)
			(layer "F.Fab")
		)
		(fp_line
			(start -0.12065 -0.2794)
			(end 0.12065 -0.2794)
			(stroke
				(width 0.1)
				(type default)
			)
			(layer "F.Fab")
		)
		(fp_line
			(start 0.120396 0.2794)
			(end -0.12065 0.2794)
			(stroke
				(width 0.1)
				(type default)
			)
			(layer "F.Fab")
		)
		(fp_line
			(start -0.12065 0.2794)
			(end -0.12065 0.3048)
			(stroke
				(width 0.1)
				(type default)
			)
			(layer "F.Fab")
		)
		(fp_line
			(start 0.67945 0.3048)
			(end 0.120396 0.3048)
			(stroke
				(width 0.1)
				(type default)
			)
			(layer "F.Fab")
		)
		(fp_line
			(start 0.120396 0.3048)
			(end 0.120396 0.2794)
			(stroke
				(width 0.1)
				(type default)
			)
			(layer "F.Fab")
		)
		(fp_line
			(start -0.12065 0.3048)
			(end -0.67945 0.3048)
			(stroke
				(width 0.1)
				(type default)
			)
			(layer "F.Fab")
		)
		(fp_line
			(start -0.67945 0.3048)
			(end -0.67945 -0.305054)
			(stroke
				(width 0.1)
				(type default)
			)
			(layer "F.Fab")
		)
		(pad "1" smd circle
			(at -0.40005 0 90)
			(size 0 0)
			(layers "F.Cu" "F.Mask" "F.Paste")
			(net "P3V3_AUX")
		)
		(pad "2" smd circle
			(at 0.40005 0 90)
			(size 0 0)
			(layers "F.Cu" "F.Mask" "F.Paste")
			(net "PWRGD_P1V8_AUX")
		)
	)
)
